(kicad_pcb
	(version 20260206)
	(generator "pcbnew")
	(generator_version "10.0")
	(general
		(thickness 1.6)
		(legacy_teardrops no)
	)
	(paper "A4")
	(title_block
		(title "peb — Lightning_PEB_BRD.brd")
		(comment 1 "Lightning (Wiwynn / Facebook NVMe JBOF) / footprints 1036-1043 of 2563")
	)
	(layers
		(0 "F.Cu" signal "TOP")
		(4 "In1.Cu" signal "L2GND")
		(6 "In2.Cu" signal "L3")
		(8 "In3.Cu" signal "L4VCC")
		(10 "In4.Cu" signal "L5VCC")
		(12 "In5.Cu" signal "L6")
		(14 "In6.Cu" signal "L7GND")
		(2 "B.Cu" signal "BOTTOM")
		(9 "F.Adhes" user "F.Adhesive")
		(11 "B.Adhes" user "B.Adhesive")
		(13 "F.Paste" user "Package Geometry/Pastemask Top")
		(15 "B.Paste" user "Package Geometry/Pastemask Bottom")
		(5 "F.SilkS" user "Ref Des/Silkscreen Top")
		(7 "B.SilkS" user "Ref Des/Silkscreen Bottom")
		(1 "F.Mask" user "Board Geometry/Soldermask Top")
		(3 "B.Mask" user "Board Geometry/Soldermask Bottom")
		(17 "Dwgs.User" user "User.Drawings")
		(19 "Cmts.User" user "User.Comments")
		(21 "Eco1.User" user "User.Eco1")
		(23 "Eco2.User" user "User.Eco2")
		(25 "Edge.Cuts" user "Board Geometry/Outline")
		(27 "Margin" user)
		(31 "F.CrtYd" user "Package Geometry/Place Bound Top")
		(29 "B.CrtYd" user "Package Geometry/Place Bound Bottom")
		(35 "F.Fab" user "Ref Des/Assembly Top")
		(33 "B.Fab" user "Ref Des/Assembly Bottom")
	)
	(footprint ""
		(layer "F.Cu")
		(at 17.946116 -94.63024)
		(property "Reference" "R2940"
			(at 0 0 0)
			(layer "F.SilkS")
			(hide yes)
			(effects
				(font
					(size 1.27 1.27)
				)
			)
		)
		(property "Value" "100KR2F-L1-GP"
			(at 0.064008 -3.993896 0)
			(unlocked yes)
			(layer "F.Fab")
			(hide yes)
			(effects
				(font
					(size 1.016 1.016)
					(thickness 0.1524)
				)
			)
		)
		(property "Device Type" "R402H16"
			(at 0.064008 -5.517896 0)
			(unlocked yes)
			(layer "F.Fab")
			(hide yes)
			(effects
				(font
					(size 1.016 1.016)
					(thickness 0.1524)
				)
			)
		)
		(duplicate_pad_numbers_are_jumpers no)
		(fp_line
			(start -0.508 -0.9398)
			(end -0.508 0.9398)
			(stroke
				(width 0.1524)
				(type default)
			)
			(layer "F.SilkS")
		)
		(fp_line
			(start 0.508 -0.9398)
			(end -0.508 -0.9398)
			(stroke
				(width 0.1524)
				(type default)
			)
			(layer "F.SilkS")
		)
		(fp_rect
			(start -0.508 0.9398)
			(end 0.508 -0.9398)
			(stroke
				(width 0)
				(type default)
			)
			(fill no)
			(layer "F.CrtYd")
		)
		(fp_rect
			(start -0.508 0.9398)
			(end 0.508 -0.9398)
			(stroke
				(width 0)
				(type default)
			)
			(fill no)
			(layer "F.Fab")
		)
		(pad "1" smd custom
			(at 0 -0.4445)
			(size 0.1397 0.1397)
			(layers "F.Cu" "F.Mask" "F.Paste")
			(net "Q20_G")
			(options
				(clearance outline)
				(anchor circle)
			)
			(primitives
				(gr_poly
					(pts
						(arc
							(start -0.1778 -0.2794)
							(mid -0.249642 -0.249642)
							(end -0.2794 -0.1778)
						)
						(arc
							(start -0.2794 0.1778)
							(mid -0.249642 0.249642)
							(end -0.1778 0.2794)
						)
						(arc
							(start 0.1778 0.2794)
							(mid 0.249642 0.249642)
							(end 0.2794 0.1778)
						)
						(arc
							(start 0.2794 -0.1778)
							(mid 0.249642 -0.249642)
							(end 0.1778 -0.2794)
						)
					)
					(width 0)
					(fill yes)
				)
			)
		)
		(pad "2" smd custom
			(at 0 0.4445)
			(size 0.1397 0.1397)
			(layers "F.Cu" "F.Mask" "F.Paste")
			(net "GND")
			(options
				(clearance outline)
				(anchor circle)
			)
			(primitives
				(gr_poly
					(pts
						(arc
							(start -0.1778 -0.2794)
							(mid -0.249642 -0.249642)
							(end -0.2794 -0.1778)
						)
						(arc
							(start -0.2794 0.1778)
							(mid -0.249642 0.249642)
							(end -0.1778 0.2794)
						)
						(arc
							(start 0.1778 0.2794)
							(mid 0.249642 0.249642)
							(end 0.2794 0.1778)
						)
						(arc
							(start 0.2794 -0.1778)
							(mid 0.249642 -0.249642)
							(end 0.1778 -0.2794)
						)
					)
					(width 0)
					(fill yes)
				)
			)
		)
	)
	(footprint ""
		(layer "F.Cu")
		(at 31.508954 -165.337744 180)
		(property "Reference" "C170"
			(at 0 0 180)
			(layer "F.SilkS")
			(hide yes)
			(effects
				(font
					(size 1.27 1.27)
				)
			)
		)
		(property "Value" "SC10U6D3V5KX-4GP"
			(at -0.0762 -6.1214 180)
			(unlocked yes)
			(layer "F.Fab")
			(hide yes)
			(effects
				(font
					(size 1.016 1.016)
					(thickness 0.1524)
				)
			)
		)
		(property "Device Type" "C805H58"
			(at -0.0762 -8.1534 180)
			(unlocked yes)
			(layer "F.Fab")
			(hide yes)
			(effects
				(font
					(size 1.016 1.016)
					(thickness 0.1524)
				)
			)
		)
		(duplicate_pad_numbers_are_jumpers no)
		(fp_line
			(start 0.635 0)
			(end -0.635 0)
			(stroke
				(width 0.508)
				(type default)
			)
			(layer "F.SilkS")
		)
		(fp_rect
			(start -0.9652 1.778)
			(end 0.9652 -1.778)
			(stroke
				(width 0)
				(type default)
			)
			(fill no)
			(layer "F.CrtYd")
		)
		(fp_poly
			(pts
				(xy -0.9652 -1.778) (xy 0.9652 -1.778) (xy 0.9652 1.778) (xy -0.9652 1.778)
			)
			(stroke
				(width 0)
				(type default)
			)
			(fill no)
			(layer "F.Fab")
		)
		(pad "1" smd rect
			(at 0 -0.9652 180)
			(size 1.397 1.143)
			(layers "F.Cu" "F.Mask" "F.Paste")
			(net "P1V53_STBY")
		)
		(pad "2" smd rect
			(at 0 0.9652 180)
			(size 1.397 1.143)
			(layers "F.Cu" "F.Mask" "F.Paste")
			(net "GND")
		)
	)
	(footprint ""
		(layer "F.Cu")
		(at 161.798 -97.5614 90)
		(property "Reference" "TP81"
			(at 0 0 90)
			(layer "F.SilkS")
			(hide yes)
			(effects
				(font
					(size 1.27 1.27)
				)
			)
		)
		(property "Value" "TPAD28-2-GP"
			(at -0.0127 -1.6637 90)
			(unlocked yes)
			(layer "F.Fab")
			(hide yes)
			(effects
				(font
					(size 1.016 1.016)
					(thickness 0.1524)
				)
			)
		)
		(property "Device Type" "TPAD28"
			(at -0.0127 -3.1877 90)
			(unlocked yes)
			(layer "F.Fab")
			(hide yes)
			(effects
				(font
					(size 1.016 1.016)
					(thickness 0.1524)
				)
			)
		)
		(duplicate_pad_numbers_are_jumpers no)
		(fp_poly
			(pts
				(arc
					(start 0 0.3556)
					(mid 0 -0.3556)
					(end 0 0.3556)
				)
			)
			(stroke
				(width 0)
				(type default)
			)
			(fill no)
			(layer "F.CrtYd")
		)
		(fp_poly
			(pts
				(arc
					(start 0 0.6096)
					(mid 0 -0.6096)
					(end 0 0.6096)
				)
			)
			(stroke
				(width 0)
				(type default)
			)
			(fill no)
			(layer "F.Fab")
		)
		(pad "1" smd circle
			(at 0 0 90)
			(size 0.7112 0.7112)
			(layers "F.Cu" "F.Mask" "F.Paste")
			(net "CLKGEN_N3")
		)
	)
	(footprint ""
		(layer "F.Cu")
		(at 346.33916 -63.022734 90)
		(property "Reference" "PC173"
			(at 0 0 90)
			(layer "F.SilkS")
			(hide yes)
			(effects
				(font
					(size 1.27 1.27)
				)
			)
		)
		(property "Value" "SC10U25V5KX-GP"
			(at -0.0762 -6.1214 90)
			(unlocked yes)
			(layer "F.Fab")
			(hide yes)
			(effects
				(font
					(size 1.016 1.016)
					(thickness 0.1524)
				)
			)
		)
		(property "Device Type" "C805H56"
			(at -0.0762 -8.1534 90)
			(unlocked yes)
			(layer "F.Fab")
			(hide yes)
			(effects
				(font
					(size 1.016 1.016)
					(thickness 0.1524)
				)
			)
		)
		(duplicate_pad_numbers_are_jumpers no)
		(fp_line
			(start 0.635 0)
			(end -0.635 0)
			(stroke
				(width 0.508)
				(type default)
			)
			(layer "F.SilkS")
		)
		(fp_rect
			(start -0.9652 1.778)
			(end 0.9652 -1.778)
			(stroke
				(width 0)
				(type default)
			)
			(fill no)
			(layer "F.CrtYd")
		)
		(fp_poly
			(pts
				(xy -0.9652 -1.778) (xy 0.9652 -1.778) (xy 0.9652 1.778) (xy -0.9652 1.778)
			)
			(stroke
				(width 0)
				(type default)
			)
			(fill no)
			(layer "F.Fab")
		)
		(pad "1" smd rect
			(at 0 -0.9652 90)
			(size 1.397 1.143)
			(layers "F.Cu" "F.Mask" "F.Paste")
			(net "P0V9_E_VIN")
		)
		(pad "2" smd rect
			(at 0 0.9652 90)
			(size 1.397 1.143)
			(layers "F.Cu" "F.Mask" "F.Paste")
			(net "GND")
		)
	)
	(footprint ""
		(layer "F.Cu")
		(at 105.408222 -212.420454 180)
		(property "Reference" "C148"
			(at 0 0 180)
			(layer "F.SilkS")
			(hide yes)
			(effects
				(font
					(size 1.27 1.27)
				)
			)
		)
		(property "Value" "SCD22U10V2KX-1GP"
			(at 1.1811 -2.7051 180)
			(unlocked yes)
			(layer "F.Fab")
			(hide yes)
			(effects
				(font
					(size 1.016 1.016)
					(thickness 0.1524)
				)
			)
		)
		(property "Device Type" "C402H22"
			(at 1.1811 -4.2291 180)
			(unlocked yes)
			(layer "F.Fab")
			(hide yes)
			(effects
				(font
					(size 1.016 1.016)
					(thickness 0.1524)
				)
			)
		)
		(duplicate_pad_numbers_are_jumpers no)
		(fp_rect
			(start -0.4318 0.9525)
			(end 0.4318 -0.9525)
			(stroke
				(width 0)
				(type default)
			)
			(fill no)
			(layer "F.CrtYd")
		)
		(fp_rect
			(start -0.4318 0.9525)
			(end 0.4318 -0.9525)
			(stroke
				(width 0)
				(type default)
			)
			(fill no)
			(layer "F.Fab")
		)
		(pad "1" smd custom
			(at 0 -0.4445 180)
			(size 0.1524 0.1524)
			(layers "F.Cu" "F.Mask" "F.Paste")
			(net "PCIE_TX_CAP_N61")
			(options
				(clearance outline)
				(anchor circle)
			)
			(primitives
				(gr_poly
					(pts
						(arc
							(start 0.3048 -0.2032)
							(mid 0.275042 -0.275042)
							(end 0.2032 -0.3048)
						)
						(arc
							(start -0.2032 -0.3048)
							(mid -0.275042 -0.275042)
							(end -0.3048 -0.2032)
						)
						(arc
							(start -0.3048 0.2032)
							(mid -0.275042 0.275042)
							(end -0.2032 0.3048)
						)
						(arc
							(start 0.2032 0.3048)
							(mid 0.275042 0.275042)
							(end 0.3048 0.2032)
						)
					)
					(width 0)
					(fill yes)
				)
			)
		)
		(pad "2" smd custom
			(at 0 0.4445 180)
			(size 0.1524 0.1524)
			(layers "F.Cu" "F.Mask" "F.Paste")
			(net "PCIE_TX_N61")
			(options
				(clearance outline)
				(anchor circle)
			)
			(primitives
				(gr_poly
					(pts
						(arc
							(start 0.3048 -0.2032)
							(mid 0.275042 -0.275042)
							(end 0.2032 -0.3048)
						)
						(arc
							(start -0.2032 -0.3048)
							(mid -0.275042 -0.275042)
							(end -0.3048 -0.2032)
						)
						(arc
							(start -0.3048 0.2032)
							(mid -0.275042 0.275042)
							(end -0.2032 0.3048)
						)
						(arc
							(start 0.2032 0.3048)
							(mid 0.275042 0.275042)
							(end 0.3048 0.2032)
						)
					)
					(width 0)
					(fill yes)
				)
			)
		)
	)
	(footprint ""
		(layer "F.Cu")
		(at 6.9342 -55.9308)
		(property "Reference" "R511"
			(at 0 0 0)
			(layer "F.SilkS")
			(hide yes)
			(effects
				(font
					(size 1.27 1.27)
				)
			)
		)
		(property "Value" "150R3J-L-GP"
			(at -0.0254 -2.5146 0)
			(unlocked yes)
			(layer "F.Fab")
			(hide yes)
			(effects
				(font
					(size 1.016 1.016)
					(thickness 0.1524)
				)
			)
		)
		(property "Device Type" "R603H22"
			(at -0.0254 -4.0386 0)
			(unlocked yes)
			(layer "F.Fab")
			(hide yes)
			(effects
				(font
					(size 1.016 1.016)
					(thickness 0.1524)
				)
			)
		)
		(duplicate_pad_numbers_are_jumpers no)
		(fp_line
			(start -0.4826 0)
			(end -0.2032 0)
			(stroke
				(width 0.2032)
				(type default)
			)
			(layer "F.SilkS")
		)
		(fp_line
			(start 0.2032 0)
			(end 0.4826 0)
			(stroke
				(width 0.2032)
				(type default)
			)
			(layer "F.SilkS")
		)
		(fp_rect
			(start -0.5842 1.3335)
			(end 0.5842 -1.3335)
			(stroke
				(width 0)
				(type default)
			)
			(fill no)
			(layer "F.CrtYd")
		)
		(fp_rect
			(start -0.5842 1.3335)
			(end 0.5842 -1.3335)
			(stroke
				(width 0)
				(type default)
			)
			(fill no)
			(layer "F.Fab")
		)
		(pad "1" smd custom
			(at 0 -0.762)
			(size 0.2159 0.2159)
			(layers "F.Cu" "F.Mask" "F.Paste")
			(net "P3V3_STBY")
			(options
				(clearance outline)
				(anchor circle)
			)
			(primitives
				(gr_poly
					(pts
						(arc
							(start -0.3302 -0.4318)
							(mid -0.402042 -0.402042)
							(end -0.4318 -0.3302)
						)
						(arc
							(start -0.4318 0.3302)
							(mid -0.402042 0.402042)
							(end -0.3302 0.4318)
						)
						(arc
							(start 0.3302 0.4318)
							(mid 0.402042 0.402042)
							(end 0.4318 0.3302)
						)
						(arc
							(start 0.4318 -0.3302)
							(mid 0.402042 -0.402042)
							(end 0.3302 -0.4318)
						)
					)
					(width 0)
					(fill yes)
				)
			)
		)
		(pad "2" smd custom
			(at 0 0.762)
			(size 0.2159 0.2159)
			(layers "F.Cu" "F.Mask" "F.Paste")
			(net "LED_MDI0_ACT")
			(options
				(clearance outline)
				(anchor circle)
			)
			(primitives
				(gr_poly
					(pts
						(arc
							(start -0.3302 -0.4318)
							(mid -0.402042 -0.402042)
							(end -0.4318 -0.3302)
						)
						(arc
							(start -0.4318 0.3302)
							(mid -0.402042 0.402042)
							(end -0.3302 0.4318)
						)
						(arc
							(start 0.3302 0.4318)
							(mid 0.402042 0.402042)
							(end 0.4318 0.3302)
						)
						(arc
							(start 0.4318 -0.3302)
							(mid 0.402042 -0.402042)
							(end 0.3302 -0.4318)
						)
					)
					(width 0)
					(fill yes)
				)
			)
		)
	)
	(footprint ""
		(layer "F.Cu")
		(at 85.449918 -5.40004)
		(property "Reference" "PAD2"
			(at 0 0 0)
			(layer "F.SilkS")
			(hide yes)
			(effects
				(font
					(size 1.27 1.27)
				)
			)
		)
		(property "Value" "PAD-3P-GP"
			(at -18.082768 -12.6492 0)
			(unlocked yes)
			(layer "F.Fab")
			(hide yes)
			(effects
				(font
					(size 1.016 1.016)
					(thickness 0.1524)
				)
			)
		)
		(property "Device Type" "HT24X28B8R32-3P-S"
			(at -18.082768 -14.1732 0)
			(unlocked yes)
			(layer "F.Fab")
			(hide yes)
			(effects
				(font
					(size 1.016 1.016)
					(thickness 0.1524)
				)
			)
		)
		(duplicate_pad_numbers_are_jumpers no)
		(fp_poly
			(pts
				(arc
					(start -6.694678 -8.800084)
					(mid -15.305278 -8.800084)
					(end -6.694678 -8.800084)
				)
			)
			(stroke
				(width 0)
				(type default)
			)
			(fill no)
			(layer "B.CrtYd")
		)
		(fp_poly
			(pts
				(arc
					(start 4.3053 -17.599914)
					(mid -4.3053 -17.599914)
					(end 4.3053 -17.599914)
				)
			)
			(stroke
				(width 0)
				(type default)
			)
			(fill no)
			(layer "B.CrtYd")
		)
		(fp_poly
			(pts
				(arc
					(start 4.3053 0)
					(mid -4.3053 0)
					(end 4.3053 0)
				)
			)
			(stroke
				(width 0)
				(type default)
			)
			(fill no)
			(layer "B.CrtYd")
		)
		(fp_poly
			(pts
				(xy -16.304768 5.70484) (xy -16.304768 -22.904704) (xy 8.304784 -22.904704) (xy 8.304784 -13.299948)
				(arc
					(start 4.99999 -13.299948)
					(mid 4.646527 -13.153539)
					(end 4.500118 -12.800076)
				)
				(arc
					(start 4.500118 -4.800092)
					(mid 4.646512 -4.446539)
					(end 4.99999 -4.299966)
				)
				(xy 8.304784 -4.299966) (xy 8.304784 5.70484)
			)
			(stroke
				(width 0)
				(type default)
			)
			(fill no)
			(layer "F.CrtYd")
		)
		(fp_poly
			(pts
				(arc
					(start -6.694678 -8.800084)
					(mid -15.305278 -8.800084)
					(end -6.694678 -8.800084)
				)
			)
			(stroke
				(width 0)
				(type default)
			)
			(fill no)
			(layer "B.Fab")
		)
		(fp_poly
			(pts
				(arc
					(start 4.3053 -17.599914)
					(mid -4.3053 -17.599914)
					(end 4.3053 -17.599914)
				)
			)
			(stroke
				(width 0)
				(type default)
			)
			(fill no)
			(layer "B.Fab")
		)
		(fp_poly
			(pts
				(arc
					(start 4.3053 0)
					(mid -4.3053 0)
					(end 4.3053 0)
				)
			)
			(stroke
				(width 0)
				(type default)
			)
			(fill no)
			(layer "B.Fab")
		)
		(fp_poly
			(pts
				(xy -16.304768 5.70484) (xy -16.304768 -22.904704) (xy 8.304784 -22.904704) (xy 8.304784 -13.299948)
				(arc
					(start 4.99999 -13.299948)
					(mid 4.646527 -13.153539)
					(end 4.500118 -12.800076)
				)
				(arc
					(start 4.500118 -4.800092)
					(mid 4.646512 -4.446539)
					(end 4.99999 -4.299966)
				)
				(xy 8.304784 -4.299966) (xy 8.304784 5.70484)
			)
			(stroke
				(width 0)
				(type default)
			)
			(fill no)
			(layer "F.Fab")
		)
		(pad "1" thru_hole custom
			(at 0 0)
			(size 5.999988 5.999988)
			(drill 3.2004)
			(layers "*.Cu" "*.Mask")
			(remove_unused_layers no)
			(net "GND")
			(clearance -9.891776)
			(thermal_gap 0.3048)
			(options
				(clearance outline)
				(anchor circle)
			)
			(primitives
				(gr_poly
					(pts
						(xy -11.999976 13.999972) (xy -11.999976 -13.999972) (xy 11.999976 -13.999972) (xy 11.999976 -5.004816)
						(arc
							(start 8.999982 -5.004816)
							(mid 8.430993 -4.769133)
							(end 8.19531 -4.200144)
						)
						(arc
							(start 8.19531 3.79984)
							(mid 8.430978 4.368919)
							(end 8.999982 4.604766)
						)
						(xy 11.999976 4.604766) (xy 11.999976 13.999972)
					)
					(width 0)
					(fill yes)
				)
			)
			(padstack
				(mode front_inner_back)
				(layer "Inner"
					(shape circle)
					(size 3.6068 3.6068)
					(clearance 0.3048)
				)
				(layer "B.Cu"
					(shape circle)
					(size 8.001 8.001)
					(clearance -1.8923)
				)
			)
		)
		(pad "2" thru_hole circle
			(at -10.999978 -8.800084)
			(size 8.001 8.001)
			(drill 3.2004)
			(layers "*.Cu" "*.Mask")
			(remove_unused_layers no)
			(net "GND")
			(clearance -1.8923)
			(thermal_gap 0.3048)
			(padstack
				(mode front_inner_back)
				(layer "Inner"
					(shape circle)
					(size 3.6068 3.6068)
					(clearance 0.3048)
				)
				(layer "B.Cu"
					(shape circle)
					(size 8.001 8.001)
					(clearance -1.8923)
				)
			)
		)
		(pad "3" thru_hole circle
			(at 0 -17.599914)
			(size 8.001 8.001)
			(drill 3.2004)
			(layers "*.Cu" "*.Mask")
			(remove_unused_layers no)
			(net "GND")
			(clearance -1.8923)
			(thermal_gap 0.3048)
			(padstack
				(mode front_inner_back)
				(layer "Inner"
					(shape circle)
					(size 3.6068 3.6068)
					(clearance 0.3048)
				)
				(layer "B.Cu"
					(shape circle)
					(size 8.001 8.001)
					(clearance -1.8923)
				)
			)
		)
	)
	(footprint ""
		(layer "F.Cu")
		(at 26.544778 -99.170236 180)
		(property "Reference" "R2950"
			(at 0 0 180)
			(layer "F.SilkS")
			(hide yes)
			(effects
				(font
					(size 1.27 1.27)
				)
			)
		)
		(property "Value" "4K75R2F-1-GP"
			(at 0.064008 -3.993896 180)
			(unlocked yes)
			(layer "F.Fab")
			(hide yes)
			(effects
				(font
					(size 1.016 1.016)
					(thickness 0.1524)
				)
			)
		)
		(property "Device Type" "R402H16"
			(at 0.064008 -5.517896 180)
			(unlocked yes)
			(layer "F.Fab")
			(hide yes)
			(effects
				(font
					(size 1.016 1.016)
					(thickness 0.1524)
				)
			)
		)
		(duplicate_pad_numbers_are_jumpers no)
		(fp_line
			(start 0.508 -0.9398)
			(end -0.508 -0.9398)
			(stroke
				(width 0.1524)
				(type default)
			)
			(layer "F.SilkS")
		)
		(fp_line
			(start -0.508 -0.9398)
			(end -0.508 0.9398)
			(stroke
				(width 0.1524)
				(type default)
			)
			(layer "F.SilkS")
		)
		(fp_rect
			(start -0.508 0.9398)
			(end 0.508 -0.9398)
			(stroke
				(width 0)
				(type default)
			)
			(fill no)
			(layer "F.CrtYd")
		)
		(fp_rect
			(start -0.508 0.9398)
			(end 0.508 -0.9398)
			(stroke
				(width 0)
				(type default)
			)
			(fill no)
			(layer "F.Fab")
		)
		(pad "1" smd custom
			(at 0 -0.4445 180)
			(size 0.1397 0.1397)
			(layers "F.Cu" "F.Mask" "F.Paste")
			(net "P3V3_STBY")
			(options
				(clearance outline)
				(anchor circle)
			)
			(primitives
				(gr_poly
					(pts
						(arc
							(start -0.1778 -0.2794)
							(mid -0.249642 -0.249642)
							(end -0.2794 -0.1778)
						)
						(arc
							(start -0.2794 0.1778)
							(mid -0.249642 0.249642)
							(end -0.1778 0.2794)
						)
						(arc
							(start 0.1778 0.2794)
							(mid 0.249642 0.249642)
							(end 0.2794 0.1778)
						)
						(arc
							(start 0.2794 -0.1778)
							(mid 0.249642 -0.249642)
							(end 0.1778 -0.2794)
						)
					)
					(width 0)
					(fill yes)
				)
			)
		)
		(pad "2" smd custom
			(at 0 0.4445 180)
			(size 0.1397 0.1397)
			(layers "F.Cu" "F.Mask" "F.Paste")
			(net "FM_TPM_PRES_RST_N_C")
			(options
				(clearance outline)
				(anchor circle)
			)
			(primitives
				(gr_poly
					(pts
						(arc
							(start -0.1778 -0.2794)
							(mid -0.249642 -0.249642)
							(end -0.2794 -0.1778)
						)
						(arc
							(start -0.2794 0.1778)
							(mid -0.249642 0.249642)
							(end -0.1778 0.2794)
						)
						(arc
							(start 0.1778 0.2794)
							(mid 0.249642 0.249642)
							(end 0.2794 0.1778)
						)
						(arc
							(start 0.2794 -0.1778)
							(mid 0.249642 -0.249642)
							(end 0.1778 -0.2794)
						)
					)
					(width 0)
					(fill yes)
				)
			)
		)
	)
)
